FILE_TYPE = CONNECTIVITY;
{Allegro Design Entry HDL 17.2-2016 S081 (4005846) 1/11/2022}
"PAGE_NUMBER" = 29;
0"NC";
1"P5E_CPU0_PE0_TX_DP<15:0>";
2"P5E_CPU0_PE0_TX_DN<15:0>";
3"P5E_CPU0_PE0_RX_DP<15:0>";
4"P5E_CPU0_PE0_RX_DN<15:0>";
5"P5E_CPU0_PE1_TX_DP<15:0>";
6"P5E_CPU0_PE1_TX_DN<15:0>";
7"P5E_CPU0_PE1_RX_DP<15:0>";
8"P5E_CPU0_PE1_RX_DN<15:0>";
9"P5E_CPU0_PE1_RX_DN<15>";
10"P5E_CPU0_PE1_RX_DN<14>";
11"P5E_CPU0_PE1_RX_DN<13>";
12"P5E_CPU0_PE1_RX_DN<12>";
13"P5E_CPU0_PE1_RX_DN<11>";
14"P5E_CPU0_PE1_RX_DN<10>";
15"P5E_CPU0_PE1_RX_DN<9>";
16"P5E_CPU0_PE1_RX_DN<8>";
17"P5E_CPU0_PE1_RX_DN<7>";
18"P5E_CPU0_PE1_RX_DN<6>";
19"P5E_CPU0_PE1_RX_DN<5>";
20"P5E_CPU0_PE1_RX_DN<4>";
21"P5E_CPU0_PE1_RX_DN<3>";
22"P5E_CPU0_PE1_RX_DN<2>";
23"P5E_CPU0_PE1_RX_DN<1>";
24"P5E_CPU0_PE1_RX_DN<0>";
25"P5E_CPU0_PE1_RX_DP<15>";
26"P5E_CPU0_PE1_RX_DP<14>";
27"P5E_CPU0_PE1_RX_DP<13>";
28"P5E_CPU0_PE1_RX_DP<12>";
29"P5E_CPU0_PE1_RX_DP<11>";
30"P5E_CPU0_PE1_RX_DP<10>";
31"P5E_CPU0_PE1_RX_DP<9>";
32"P5E_CPU0_PE1_RX_DP<8>";
33"P5E_CPU0_PE1_RX_DP<7>";
34"P5E_CPU0_PE1_RX_DP<6>";
35"P5E_CPU0_PE1_RX_DP<5>";
36"P5E_CPU0_PE1_RX_DP<4>";
37"P5E_CPU0_PE1_RX_DP<3>";
38"P5E_CPU0_PE1_RX_DP<2>";
39"P5E_CPU0_PE1_RX_DP<1>";
40"P5E_CPU0_PE1_RX_DP<0>";
41"P5E_CPU0_PE1_TX_DN<15>";
42"P5E_CPU0_PE1_TX_DN<14>";
43"P5E_CPU0_PE1_TX_DN<13>";
44"P5E_CPU0_PE1_TX_DN<12>";
45"P5E_CPU0_PE1_TX_DN<11>";
46"P5E_CPU0_PE1_TX_DN<10>";
47"P5E_CPU0_PE1_TX_DN<9>";
48"P5E_CPU0_PE1_TX_DN<8>";
49"P5E_CPU0_PE1_TX_DN<7>";
50"P5E_CPU0_PE1_TX_DN<6>";
51"P5E_CPU0_PE1_TX_DN<5>";
52"P5E_CPU0_PE1_TX_DN<4>";
53"P5E_CPU0_PE1_TX_DN<3>";
54"P5E_CPU0_PE1_TX_DN<2>";
55"P5E_CPU0_PE1_TX_DN<1>";
56"P5E_CPU0_PE1_TX_DN<0>";
57"P5E_CPU0_PE1_TX_DP<15>";
58"P5E_CPU0_PE1_TX_DP<14>";
59"P5E_CPU0_PE1_TX_DP<13>";
60"P5E_CPU0_PE1_TX_DP<12>";
61"P5E_CPU0_PE1_TX_DP<11>";
62"P5E_CPU0_PE1_TX_DP<10>";
63"P5E_CPU0_PE1_TX_DP<9>";
64"P5E_CPU0_PE1_TX_DP<8>";
65"P5E_CPU0_PE1_TX_DP<7>";
66"P5E_CPU0_PE1_TX_DP<6>";
67"P5E_CPU0_PE1_TX_DP<5>";
68"P5E_CPU0_PE1_TX_DP<4>";
69"P5E_CPU0_PE1_TX_DP<3>";
70"P5E_CPU0_PE1_TX_DP<2>";
71"P5E_CPU0_PE1_TX_DP<1>";
72"P5E_CPU0_PE1_TX_DP<0>";
73"P5E_CPU0_PE0_RX_DN<15>";
74"P5E_CPU0_PE0_RX_DN<14>";
75"P5E_CPU0_PE0_RX_DN<13>";
76"P5E_CPU0_PE0_RX_DN<12>";
77"P5E_CPU0_PE0_RX_DN<11>";
78"P5E_CPU0_PE0_RX_DN<10>";
79"P5E_CPU0_PE0_RX_DN<9>";
80"P5E_CPU0_PE0_RX_DN<8>";
81"P5E_CPU0_PE0_RX_DN<7>";
82"P5E_CPU0_PE0_RX_DN<6>";
83"P5E_CPU0_PE0_RX_DN<5>";
84"P5E_CPU0_PE0_RX_DN<4>";
85"P5E_CPU0_PE0_RX_DN<3>";
86"P5E_CPU0_PE0_RX_DN<2>";
87"P5E_CPU0_PE0_RX_DN<1>";
88"P5E_CPU0_PE0_RX_DN<0>";
89"P5E_CPU0_PE0_RX_DP<15>";
90"P5E_CPU0_PE0_RX_DP<14>";
91"P5E_CPU0_PE0_RX_DP<13>";
92"P5E_CPU0_PE0_RX_DP<12>";
93"P5E_CPU0_PE0_RX_DP<11>";
94"P5E_CPU0_PE0_RX_DP<10>";
95"P5E_CPU0_PE0_RX_DP<9>";
96"P5E_CPU0_PE0_RX_DP<8>";
97"P5E_CPU0_PE0_RX_DP<7>";
98"P5E_CPU0_PE0_RX_DP<6>";
99"P5E_CPU0_PE0_RX_DP<5>";
100"P5E_CPU0_PE0_RX_DP<4>";
101"P5E_CPU0_PE0_RX_DP<3>";
102"P5E_CPU0_PE0_RX_DP<2>";
103"P5E_CPU0_PE0_RX_DP<1>";
104"P5E_CPU0_PE0_RX_DP<0>";
105"P5E_CPU0_PE0_TX_DN<15>";
106"P5E_CPU0_PE0_TX_DN<14>";
107"P5E_CPU0_PE0_TX_DN<13>";
108"P5E_CPU0_PE0_TX_DN<12>";
109"P5E_CPU0_PE0_TX_DN<11>";
110"P5E_CPU0_PE0_TX_DN<10>";
111"P5E_CPU0_PE0_TX_DN<9>";
112"P5E_CPU0_PE0_TX_DN<8>";
113"P5E_CPU0_PE0_TX_DN<7>";
114"P5E_CPU0_PE0_TX_DN<6>";
115"P5E_CPU0_PE0_TX_DN<5>";
116"P5E_CPU0_PE0_TX_DN<4>";
117"P5E_CPU0_PE0_TX_DN<3>";
118"P5E_CPU0_PE0_TX_DN<2>";
119"P5E_CPU0_PE0_TX_DN<1>";
120"P5E_CPU0_PE0_TX_DN<0>";
121"P5E_CPU0_PE0_TX_DP<15>";
122"P5E_CPU0_PE0_TX_DP<14>";
123"P5E_CPU0_PE0_TX_DP<13>";
124"P5E_CPU0_PE0_TX_DP<12>";
125"P5E_CPU0_PE0_TX_DP<11>";
126"P5E_CPU0_PE0_TX_DP<10>";
127"P5E_CPU0_PE0_TX_DP<9>";
128"P5E_CPU0_PE0_TX_DP<8>";
129"P5E_CPU0_PE0_TX_DP<7>";
130"P5E_CPU0_PE0_TX_DP<6>";
131"P5E_CPU0_PE0_TX_DP<5>";
132"P5E_CPU0_PE0_TX_DP<4>";
133"P5E_CPU0_PE0_TX_DP<3>";
134"P5E_CPU0_PE0_TX_DP<2>";
135"P5E_CPU0_PE0_TX_DP<1>";
136"P5E_CPU0_PE0_TX_DP<0>";
%"SOCKET4677_AZIF0045P001C01CS"
"18","(1400,325)","0","pure_quanta","I176";
;
PART_NUMBER"DGA^7000023"
VALUE"SOCKET4677_AZIF0045-P001C01CS"
MATERIAL"IO"
PART_TYPE"SMLF"
$LOCATION"U2"
CDS_LMAN_SYM_OUTLINE"-1050,950,1050,-950"
NEEDS_NO_SIZE"TRUE"
CDS_LIB"pure_quanta"
CDS_LOCATION"U2"
$SEC"18"
CDS_SEC"18";
"PE1_TX_DP0"
$PN"CR15"72;
"PE1_TX_DP1"
$PN"CM14"71;
"PE1_TX_DP2"
$PN"CL15"70;
"PE1_TX_DP3"
$PN"CH14"69;
"PE1_TX_DP4"
$PN"CG15"68;
"PE1_TX_DP5"
$PN"CD14"67;
"PE1_TX_DP6"
$PN"CC15"66;
"PE1_TX_DP7"
$PN"BY14"65;
"PE1_TX_DP8"
$PN"BW15"64;
"PE1_TX_DP9"
$PN"BT14"63;
"PE1_TX_DP10"
$PN"BR15"62;
"PE1_TX_DP11"
$PN"BM14"61;
"PE1_TX_DP12"
$PN"BL15"60;
"PE1_TX_DP13"
$PN"BH14"59;
"PE1_TX_DP14"
$PN"BG15"58;
"PE1_TX_DP15"
$PN"BD14"57;
"PE1_TX_DN0"
$PN"CP14"56;
"PE1_TX_DN1"
$PN"CN13"55;
"PE1_TX_DN2"
$PN"CK14"54;
"PE1_TX_DN3"
$PN"CJ13"53;
"PE1_TX_DN4"
$PN"CF14"52;
"PE1_TX_DN5"
$PN"CE13"51;
"PE1_TX_DN6"
$PN"CB14"50;
"PE1_TX_DN7"
$PN"CA13"49;
"PE1_TX_DN8"
$PN"BV14"48;
"PE1_TX_DN9"
$PN"BU13"47;
"PE1_TX_DN10"
$PN"BP14"46;
"PE1_TX_DN11"
$PN"BN13"45;
"PE1_TX_DN12"
$PN"BK14"44;
"PE1_TX_DN13"
$PN"BJ13"43;
"PE1_TX_DN14"
$PN"BF14"42;
"PE1_TX_DN15"
$PN"BE13"41;
"PE1_RX_DP0"
$PN"CN9"40;
"PE1_RX_DP1"
$PN"CM10"39;
"PE1_RX_DP2"
$PN"CJ9"38;
"PE1_RX_DP3"
$PN"CH10"37;
"PE1_RX_DP4"
$PN"CE9"36;
"PE1_RX_DP5"
$PN"CD10"35;
"PE1_RX_DP6"
$PN"CA9"34;
"PE1_RX_DP7"
$PN"BY10"33;
"PE1_RX_DP8"
$PN"BU9"32;
"PE1_RX_DP9"
$PN"BT10"31;
"PE1_RX_DP10"
$PN"BN9"30;
"PE1_RX_DP11"
$PN"BM10"29;
"PE1_RX_DP12"
$PN"BJ9"28;
"PE1_RX_DP13"
$PN"BH10"27;
"PE1_RX_DP14"
$PN"BE9"26;
"PE1_RX_DP15"
$PN"BD10"25;
"PE1_RX_DN0"
$PN"CP10"24;
"PE1_RX_DN1"
$PN"CL11"23;
"PE1_RX_DN2"
$PN"CK10"22;
"PE1_RX_DN3"
$PN"CG11"21;
"PE1_RX_DN4"
$PN"CF10"20;
"PE1_RX_DN5"
$PN"CC11"19;
"PE1_RX_DN6"
$PN"CB10"18;
"PE1_RX_DN7"
$PN"BW11"17;
"PE1_RX_DN8"
$PN"BV10"16;
"PE1_RX_DN9"
$PN"BR11"15;
"PE1_RX_DN10"
$PN"BP10"14;
"PE1_RX_DN11"
$PN"BL11"13;
"PE1_RX_DN12"
$PN"BK10"12;
"PE1_RX_DN13"
$PN"BG11"11;
"PE1_RX_DN14"
$PN"BF10"10;
"PE1_RX_DN15"
$PN"BC11"9;
%"SOCKET4677_AZIF0045P001C01CS"
"17","(1400,3075)","0","pure_quanta","I37";
;
PART_NUMBER"DGA^7000023"
VALUE"SOCKET4677_AZIF0045-P001C01CS"
MATERIAL"IO"
PART_TYPE"SMLF"
$LOCATION"U2"
CDS_LMAN_SYM_OUTLINE"-1050,950,1050,-950"
NEEDS_NO_SIZE"TRUE"
CDS_LIB"pure_quanta"
CDS_LOCATION"U2"
$SEC"17"
CDS_SEC"17";
"PE0_TX_DP0"
$PN"M14"136;
"PE0_TX_DP1"
$PN"R15"135;
"PE0_TX_DP2"
$PN"T14"134;
"PE0_TX_DP3"
$PN"W15"133;
"PE0_TX_DP4"
$PN"Y14"132;
"PE0_TX_DP5"
$PN"AC15"131;
"PE0_TX_DP6"
$PN"AD14"130;
"PE0_TX_DP7"
$PN"AG15"129;
"PE0_TX_DP8"
$PN"AH14"128;
"PE0_TX_DP9"
$PN"AL15"127;
"PE0_TX_DP10"
$PN"AM14"126;
"PE0_TX_DP11"
$PN"AR15"125;
"PE0_TX_DP12"
$PN"AT14"124;
"PE0_TX_DP13"
$PN"AW15"123;
"PE0_TX_DP14"
$PN"AY14"122;
"PE0_TX_DP15"
$PN"BC15"121;
"PE0_TX_DN0"
$PN"N13"120;
"PE0_TX_DN1"
$PN"P14"119;
"PE0_TX_DN2"
$PN"U13"118;
"PE0_TX_DN3"
$PN"V14"117;
"PE0_TX_DN4"
$PN"AA13"116;
"PE0_TX_DN5"
$PN"AB14"115;
"PE0_TX_DN6"
$PN"AE13"114;
"PE0_TX_DN7"
$PN"AF14"113;
"PE0_TX_DN8"
$PN"AJ13"112;
"PE0_TX_DN9"
$PN"AK14"111;
"PE0_TX_DN10"
$PN"AN13"110;
"PE0_TX_DN11"
$PN"AP14"109;
"PE0_TX_DN12"
$PN"AU13"108;
"PE0_TX_DN13"
$PN"AV14"107;
"PE0_TX_DN14"
$PN"BA13"106;
"PE0_TX_DN15"
$PN"BB14"105;
"PE0_RX_DP0"
$PN"L11"104;
"PE0_RX_DP1"
$PN"N9"103;
"PE0_RX_DP2"
$PN"R11"102;
"PE0_RX_DP3"
$PN"U9"101;
"PE0_RX_DP4"
$PN"W11"100;
"PE0_RX_DP5"
$PN"Y10"99;
"PE0_RX_DP6"
$PN"AC11"98;
"PE0_RX_DP7"
$PN"AD10"97;
"PE0_RX_DP8"
$PN"AG11"96;
"PE0_RX_DP9"
$PN"AH10"95;
"PE0_RX_DP10"
$PN"AL11"94;
"PE0_RX_DP11"
$PN"AN9"93;
"PE0_RX_DP12"
$PN"AR11"92;
"PE0_RX_DP13"
$PN"AT10"91;
"PE0_RX_DP14"
$PN"AW11"90;
"PE0_RX_DP15"
$PN"AY10"89;
"PE0_RX_DN0"
$PN"K10"88;
"PE0_RX_DN1"
$PN"M10"87;
"PE0_RX_DN2"
$PN"P10"86;
"PE0_RX_DN3"
$PN"T10"85;
"PE0_RX_DN4"
$PN"V10"84;
"PE0_RX_DN5"
$PN"AA9"83;
"PE0_RX_DN6"
$PN"AB10"82;
"PE0_RX_DN7"
$PN"AE9"81;
"PE0_RX_DN8"
$PN"AF10"80;
"PE0_RX_DN9"
$PN"AJ9"79;
"PE0_RX_DN10"
$PN"AK10"78;
"PE0_RX_DN11"
$PN"AM10"77;
"PE0_RX_DN12"
$PN"AP10"76;
"PE0_RX_DN13"
$PN"AU9"75;
"PE0_RX_DN14"
$PN"AV10"74;
"PE0_RX_DN15"
$PN"BA9"73;
%"TAP"
"1","(-275,2275)","2","standard","I404";
;
CDS_LIB"standard"
BODY_TYPE"PLUMBING"
HDL_TAP"TRUE";
"B \NAC \NWC"4;
"S \NAC"
BN"0"88;
%"TAP"
"1","(-275,2325)","2","standard","I405";
;
CDS_LIB"standard"
BODY_TYPE"PLUMBING"
HDL_TAP"TRUE";
"B \NAC \NWC"4;
"S \NAC"
BN"1"87;
%"TAP"
"1","(-275,2425)","2","standard","I406";
;
CDS_LIB"standard"
BODY_TYPE"PLUMBING"
HDL_TAP"TRUE";
"B \NAC \NWC"4;
"S \NAC"
BN"3"85;
%"TAP"
"1","(-275,2375)","2","standard","I407";
;
CDS_LIB"standard"
BODY_TYPE"PLUMBING"
HDL_TAP"TRUE";
"B \NAC \NWC"4;
"S \NAC"
BN"2"86;
%"TAP"
"1","(-275,2525)","2","standard","I408";
;
CDS_LIB"standard"
BODY_TYPE"PLUMBING"
HDL_TAP"TRUE";
"B \NAC \NWC"4;
"S \NAC"
BN"5"83;
%"TAP"
"1","(-275,2475)","2","standard","I409";
;
CDS_LIB"standard"
BODY_TYPE"PLUMBING"
HDL_TAP"TRUE";
"B \NAC \NWC"4;
"S \NAC"
BN"4"84;
%"TAP"
"1","(-275,2575)","2","standard","I410";
;
CDS_LIB"standard"
BODY_TYPE"PLUMBING"
HDL_TAP"TRUE";
"B \NAC \NWC"4;
"S \NAC"
BN"6"82;
%"TAP"
"1","(-275,2675)","2","standard","I411";
;
CDS_LIB"standard"
BODY_TYPE"PLUMBING"
HDL_TAP"TRUE";
"B \NAC \NWC"4;
"S \NAC"
BN"8"80;
%"TAP"
"1","(-275,2625)","2","standard","I412";
;
CDS_LIB"standard"
BODY_TYPE"PLUMBING"
HDL_TAP"TRUE";
"B \NAC \NWC"4;
"S \NAC"
BN"7"81;
%"TAP"
"1","(-275,2775)","2","standard","I413";
;
CDS_LIB"standard"
BODY_TYPE"PLUMBING"
HDL_TAP"TRUE";
"B \NAC \NWC"4;
"S \NAC"
BN"10"78;
%"TAP"
"1","(-275,2725)","2","standard","I414";
;
CDS_LIB"standard"
BODY_TYPE"PLUMBING"
HDL_TAP"TRUE";
"B \NAC \NWC"4;
"S \NAC"
BN"9"79;
%"TAP"
"1","(-275,2825)","2","standard","I415";
;
CDS_LIB"standard"
BODY_TYPE"PLUMBING"
HDL_TAP"TRUE";
"B \NAC \NWC"4;
"S \NAC"
BN"11"77;
%"TAP"
"1","(-275,2925)","2","standard","I416";
;
CDS_LIB"standard"
BODY_TYPE"PLUMBING"
HDL_TAP"TRUE";
"B \NAC \NWC"4;
"S \NAC"
BN"13"75;
%"TAP"
"1","(-275,2875)","2","standard","I417";
;
CDS_LIB"standard"
BODY_TYPE"PLUMBING"
HDL_TAP"TRUE";
"B \NAC \NWC"4;
"S \NAC"
BN"12"76;
%"TAP"
"1","(-275,2975)","2","standard","I418";
;
CDS_LIB"standard"
BODY_TYPE"PLUMBING"
HDL_TAP"TRUE";
"B \NAC \NWC"4;
"S \NAC"
BN"14"74;
%"TAP"
"1","(-275,3025)","2","standard","I419";
;
CDS_LIB"standard"
BODY_TYPE"PLUMBING"
HDL_TAP"TRUE";
"B \NAC \NWC"4;
"S \NAC"
BN"15"73;
%"TAP"
"1","(-275,3125)","2","standard","I420";
;
CDS_LIB"standard"
BODY_TYPE"PLUMBING"
HDL_TAP"TRUE";
"B \NAC \NWC"3;
"S \NAC"
BN"0"104;
%"TAP"
"1","(-275,3175)","2","standard","I421";
;
CDS_LIB"standard"
BODY_TYPE"PLUMBING"
HDL_TAP"TRUE";
"B \NAC \NWC"3;
"S \NAC"
BN"1"103;
%"TAP"
"1","(-275,3225)","2","standard","I422";
;
CDS_LIB"standard"
BODY_TYPE"PLUMBING"
HDL_TAP"TRUE";
"B \NAC \NWC"3;
"S \NAC"
BN"2"102;
%"TAP"
"1","(-275,3275)","2","standard","I423";
;
CDS_LIB"standard"
BODY_TYPE"PLUMBING"
HDL_TAP"TRUE";
"B \NAC \NWC"3;
"S \NAC"
BN"3"101;
%"TAP"
"1","(-275,3325)","2","standard","I424";
;
CDS_LIB"standard"
BODY_TYPE"PLUMBING"
HDL_TAP"TRUE";
"B \NAC \NWC"3;
"S \NAC"
BN"4"100;
%"TAP"
"1","(-275,3375)","2","standard","I425";
;
CDS_LIB"standard"
BODY_TYPE"PLUMBING"
HDL_TAP"TRUE";
"B \NAC \NWC"3;
"S \NAC"
BN"5"99;
%"TAP"
"1","(-275,3425)","2","standard","I426";
;
CDS_LIB"standard"
BODY_TYPE"PLUMBING"
HDL_TAP"TRUE";
"B \NAC \NWC"3;
"S \NAC"
BN"6"98;
%"TAP"
"1","(-275,3475)","2","standard","I427";
;
CDS_LIB"standard"
BODY_TYPE"PLUMBING"
HDL_TAP"TRUE";
"B \NAC \NWC"3;
"S \NAC"
BN"7"97;
%"TAP"
"1","(-275,3525)","2","standard","I428";
;
CDS_LIB"standard"
BODY_TYPE"PLUMBING"
HDL_TAP"TRUE";
"B \NAC \NWC"3;
"S \NAC"
BN"8"96;
%"TAP"
"1","(-275,3575)","2","standard","I429";
;
CDS_LIB"standard"
BODY_TYPE"PLUMBING"
HDL_TAP"TRUE";
"B \NAC \NWC"3;
"S \NAC"
BN"9"95;
%"TAP"
"1","(-275,3625)","2","standard","I430";
;
CDS_LIB"standard"
BODY_TYPE"PLUMBING"
HDL_TAP"TRUE";
"B \NAC \NWC"3;
"S \NAC"
BN"10"94;
%"TAP"
"1","(-275,3675)","2","standard","I431";
;
CDS_LIB"standard"
BODY_TYPE"PLUMBING"
HDL_TAP"TRUE";
"B \NAC \NWC"3;
"S \NAC"
BN"11"93;
%"TAP"
"1","(-275,3725)","2","standard","I432";
;
CDS_LIB"standard"
BODY_TYPE"PLUMBING"
HDL_TAP"TRUE";
"B \NAC \NWC"3;
"S \NAC"
BN"12"92;
%"TAP"
"1","(-275,3775)","2","standard","I433";
;
CDS_LIB"standard"
BODY_TYPE"PLUMBING"
HDL_TAP"TRUE";
"B \NAC \NWC"3;
"S \NAC"
BN"13"91;
%"TAP"
"1","(-275,3825)","2","standard","I434";
;
CDS_LIB"standard"
BODY_TYPE"PLUMBING"
HDL_TAP"TRUE";
"B \NAC \NWC"3;
"S \NAC"
BN"14"90;
%"TAP"
"1","(-275,3875)","2","standard","I435";
;
CDS_LIB"standard"
BODY_TYPE"PLUMBING"
HDL_TAP"TRUE";
"B \NAC \NWC"3;
"S \NAC"
BN"15"89;
%"TAP"
"1","(-275,1125)","2","standard","I436";
;
CDS_LIB"standard"
BODY_TYPE"PLUMBING"
HDL_TAP"TRUE";
"B \NAC \NWC"7;
"S \NAC"
BN"15"25;
%"TAP"
"1","(-275,1075)","2","standard","I437";
;
CDS_LIB"standard"
BODY_TYPE"PLUMBING"
HDL_TAP"TRUE";
"B \NAC \NWC"7;
"S \NAC"
BN"14"26;
%"TAP"
"1","(-275,1025)","2","standard","I438";
;
CDS_LIB"standard"
BODY_TYPE"PLUMBING"
HDL_TAP"TRUE";
"B \NAC \NWC"7;
"S \NAC"
BN"13"27;
%"TAP"
"1","(-275,975)","2","standard","I439";
;
CDS_LIB"standard"
BODY_TYPE"PLUMBING"
HDL_TAP"TRUE";
"B \NAC \NWC"7;
"S \NAC"
BN"12"28;
%"TAP"
"1","(-275,925)","2","standard","I440";
;
CDS_LIB"standard"
BODY_TYPE"PLUMBING"
HDL_TAP"TRUE";
"B \NAC \NWC"7;
"S \NAC"
BN"11"29;
%"TAP"
"1","(-275,875)","2","standard","I441";
;
CDS_LIB"standard"
BODY_TYPE"PLUMBING"
HDL_TAP"TRUE";
"B \NAC \NWC"7;
"S \NAC"
BN"10"30;
%"TAP"
"1","(-275,825)","2","standard","I442";
;
CDS_LIB"standard"
BODY_TYPE"PLUMBING"
HDL_TAP"TRUE";
"B \NAC \NWC"7;
"S \NAC"
BN"9"31;
%"TAP"
"1","(-275,725)","2","standard","I443";
;
CDS_LIB"standard"
BODY_TYPE"PLUMBING"
HDL_TAP"TRUE";
"B \NAC \NWC"7;
"S \NAC"
BN"7"33;
%"TAP"
"1","(-275,775)","2","standard","I444";
;
CDS_LIB"standard"
BODY_TYPE"PLUMBING"
HDL_TAP"TRUE";
"B \NAC \NWC"7;
"S \NAC"
BN"8"32;
%"TAP"
"1","(-275,675)","2","standard","I445";
;
CDS_LIB"standard"
BODY_TYPE"PLUMBING"
HDL_TAP"TRUE";
"B \NAC \NWC"7;
"S \NAC"
BN"6"34;
%"TAP"
"1","(-275,625)","2","standard","I446";
;
CDS_LIB"standard"
BODY_TYPE"PLUMBING"
HDL_TAP"TRUE";
"B \NAC \NWC"7;
"S \NAC"
BN"5"35;
%"TAP"
"1","(-275,575)","2","standard","I447";
;
CDS_LIB"standard"
BODY_TYPE"PLUMBING"
HDL_TAP"TRUE";
"B \NAC \NWC"7;
"S \NAC"
BN"4"36;
%"TAP"
"1","(-275,475)","2","standard","I448";
;
CDS_LIB"standard"
BODY_TYPE"PLUMBING"
HDL_TAP"TRUE";
"B \NAC \NWC"7;
"S \NAC"
BN"2"38;
%"TAP"
"1","(-275,525)","2","standard","I449";
;
CDS_LIB"standard"
BODY_TYPE"PLUMBING"
HDL_TAP"TRUE";
"B \NAC \NWC"7;
"S \NAC"
BN"3"37;
%"TAP"
"1","(-275,425)","2","standard","I450";
;
CDS_LIB"standard"
BODY_TYPE"PLUMBING"
HDL_TAP"TRUE";
"B \NAC \NWC"7;
"S \NAC"
BN"1"39;
%"TAP"
"1","(-275,375)","2","standard","I451";
;
CDS_LIB"standard"
BODY_TYPE"PLUMBING"
HDL_TAP"TRUE";
"B \NAC \NWC"7;
"S \NAC"
BN"0"40;
%"TAP"
"1","(-275,275)","2","standard","I452";
;
CDS_LIB"standard"
BODY_TYPE"PLUMBING"
HDL_TAP"TRUE";
"B \NAC \NWC"8;
"S \NAC"
BN"15"9;
%"TAP"
"1","(-275,175)","2","standard","I453";
;
CDS_LIB"standard"
BODY_TYPE"PLUMBING"
HDL_TAP"TRUE";
"B \NAC \NWC"8;
"S \NAC"
BN"13"11;
%"TAP"
"1","(-275,225)","2","standard","I454";
;
CDS_LIB"standard"
BODY_TYPE"PLUMBING"
HDL_TAP"TRUE";
"B \NAC \NWC"8;
"S \NAC"
BN"14"10;
%"TAP"
"1","(-275,125)","2","standard","I455";
;
CDS_LIB"standard"
BODY_TYPE"PLUMBING"
HDL_TAP"TRUE";
"B \NAC \NWC"8;
"S \NAC"
BN"12"12;
%"TAP"
"1","(-275,75)","2","standard","I456";
;
CDS_LIB"standard"
BODY_TYPE"PLUMBING"
HDL_TAP"TRUE";
"B \NAC \NWC"8;
"S \NAC"
BN"11"13;
%"TAP"
"1","(-275,25)","2","standard","I457";
;
CDS_LIB"standard"
BODY_TYPE"PLUMBING"
HDL_TAP"TRUE";
"B \NAC \NWC"8;
"S \NAC"
BN"10"14;
%"TAP"
"1","(-275,-25)","2","standard","I458";
;
CDS_LIB"standard"
BODY_TYPE"PLUMBING"
HDL_TAP"TRUE";
"B \NAC \NWC"8;
"S \NAC"
BN"9"15;
%"TAP"
"1","(-275,-75)","2","standard","I459";
;
CDS_LIB"standard"
BODY_TYPE"PLUMBING"
HDL_TAP"TRUE";
"B \NAC \NWC"8;
"S \NAC"
BN"8"16;
%"TAP"
"1","(-275,-175)","2","standard","I460";
;
CDS_LIB"standard"
BODY_TYPE"PLUMBING"
HDL_TAP"TRUE";
"B \NAC \NWC"8;
"S \NAC"
BN"6"18;
%"TAP"
"1","(-275,-125)","2","standard","I461";
;
CDS_LIB"standard"
BODY_TYPE"PLUMBING"
HDL_TAP"TRUE";
"B \NAC \NWC"8;
"S \NAC"
BN"7"17;
%"TAP"
"1","(-275,-225)","2","standard","I462";
;
CDS_LIB"standard"
BODY_TYPE"PLUMBING"
HDL_TAP"TRUE";
"B \NAC \NWC"8;
"S \NAC"
BN"5"19;
%"TAP"
"1","(-275,-275)","2","standard","I463";
;
CDS_LIB"standard"
BODY_TYPE"PLUMBING"
HDL_TAP"TRUE";
"B \NAC \NWC"8;
"S \NAC"
BN"4"20;
%"TAP"
"1","(-275,-325)","2","standard","I464";
;
CDS_LIB"standard"
BODY_TYPE"PLUMBING"
HDL_TAP"TRUE";
"B \NAC \NWC"8;
"S \NAC"
BN"3"21;
%"TAP"
"1","(-275,-425)","2","standard","I465";
;
CDS_LIB"standard"
BODY_TYPE"PLUMBING"
HDL_TAP"TRUE";
"B \NAC \NWC"8;
"S \NAC"
BN"1"23;
%"TAP"
"1","(-275,-375)","2","standard","I466";
;
CDS_LIB"standard"
BODY_TYPE"PLUMBING"
HDL_TAP"TRUE";
"B \NAC \NWC"8;
"S \NAC"
BN"2"22;
%"TAP"
"1","(-275,-475)","2","standard","I467";
;
CDS_LIB"standard"
BODY_TYPE"PLUMBING"
HDL_TAP"TRUE";
"B \NAC \NWC"8;
"S \NAC"
BN"0"24;
%"TAP"
"1","(3125,2375)","0","standard","I470";
;
CDS_LIB"standard"
BODY_TYPE"PLUMBING"
HDL_TAP"TRUE";
"B \NAC \NWC"2;
"S \NAC"
BN"2"118;
%"TAP"
"1","(3125,2325)","0","standard","I471";
;
CDS_LIB"standard"
BODY_TYPE"PLUMBING"
HDL_TAP"TRUE";
"B \NAC \NWC"2;
"S \NAC"
BN"1"119;
%"TAP"
"1","(3125,2275)","0","standard","I472";
;
CDS_LIB"standard"
BODY_TYPE"PLUMBING"
HDL_TAP"TRUE";
"B \NAC \NWC"2;
"S \NAC"
BN"0"120;
%"TAP"
"1","(3125,2475)","0","standard","I473";
;
CDS_LIB"standard"
BODY_TYPE"PLUMBING"
HDL_TAP"TRUE";
"B \NAC \NWC"2;
"S \NAC"
BN"4"116;
%"TAP"
"1","(3125,2425)","0","standard","I474";
;
CDS_LIB"standard"
BODY_TYPE"PLUMBING"
HDL_TAP"TRUE";
"B \NAC \NWC"2;
"S \NAC"
BN"3"117;
%"TAP"
"1","(3125,2625)","0","standard","I475";
;
CDS_LIB"standard"
BODY_TYPE"PLUMBING"
HDL_TAP"TRUE";
"B \NAC \NWC"2;
"S \NAC"
BN"7"113;
%"TAP"
"1","(3125,2575)","0","standard","I476";
;
CDS_LIB"standard"
BODY_TYPE"PLUMBING"
HDL_TAP"TRUE";
"B \NAC \NWC"2;
"S \NAC"
BN"6"114;
%"TAP"
"1","(3125,2525)","0","standard","I477";
;
CDS_LIB"standard"
BODY_TYPE"PLUMBING"
HDL_TAP"TRUE";
"B \NAC \NWC"2;
"S \NAC"
BN"5"115;
%"TAP"
"1","(3125,2675)","0","standard","I478";
;
CDS_LIB"standard"
BODY_TYPE"PLUMBING"
HDL_TAP"TRUE";
"B \NAC \NWC"2;
"S \NAC"
BN"8"112;
%"TAP"
"1","(3125,2725)","0","standard","I479";
;
CDS_LIB"standard"
BODY_TYPE"PLUMBING"
HDL_TAP"TRUE";
"B \NAC \NWC"2;
"S \NAC"
BN"9"111;
%"TAP"
"1","(3125,2875)","0","standard","I480";
;
CDS_LIB"standard"
BODY_TYPE"PLUMBING"
HDL_TAP"TRUE";
"B \NAC \NWC"2;
"S \NAC"
BN"12"108;
%"TAP"
"1","(3125,2775)","0","standard","I481";
;
CDS_LIB"standard"
BODY_TYPE"PLUMBING"
HDL_TAP"TRUE";
"B \NAC \NWC"2;
"S \NAC"
BN"10"110;
%"TAP"
"1","(3125,2825)","0","standard","I482";
;
CDS_LIB"standard"
BODY_TYPE"PLUMBING"
HDL_TAP"TRUE";
"B \NAC \NWC"2;
"S \NAC"
BN"11"109;
%"TAP"
"1","(3125,2925)","0","standard","I483";
;
CDS_LIB"standard"
BODY_TYPE"PLUMBING"
HDL_TAP"TRUE";
"B \NAC \NWC"2;
"S \NAC"
BN"13"107;
%"TAP"
"1","(3125,2975)","0","standard","I484";
;
CDS_LIB"standard"
BODY_TYPE"PLUMBING"
HDL_TAP"TRUE";
"B \NAC \NWC"2;
"S \NAC"
BN"14"106;
%"TAP"
"1","(3125,3025)","0","standard","I485";
;
CDS_LIB"standard"
BODY_TYPE"PLUMBING"
HDL_TAP"TRUE";
"B \NAC \NWC"2;
"S \NAC"
BN"15"105;
%"TAP"
"1","(3125,3125)","0","standard","I486";
;
CDS_LIB"standard"
BODY_TYPE"PLUMBING"
HDL_TAP"TRUE";
"B \NAC \NWC"1;
"S \NAC"
BN"0"136;
%"TAP"
"1","(3125,3275)","0","standard","I487";
;
CDS_LIB"standard"
BODY_TYPE"PLUMBING"
HDL_TAP"TRUE";
"B \NAC \NWC"1;
"S \NAC"
BN"3"133;
%"TAP"
"1","(3125,3175)","0","standard","I488";
;
CDS_LIB"standard"
BODY_TYPE"PLUMBING"
HDL_TAP"TRUE";
"B \NAC \NWC"1;
"S \NAC"
BN"1"135;
%"TAP"
"1","(3125,3225)","0","standard","I489";
;
CDS_LIB"standard"
BODY_TYPE"PLUMBING"
HDL_TAP"TRUE";
"B \NAC \NWC"1;
"S \NAC"
BN"2"134;
%"TAP"
"1","(3125,3375)","0","standard","I490";
;
CDS_LIB"standard"
BODY_TYPE"PLUMBING"
HDL_TAP"TRUE";
"B \NAC \NWC"1;
"S \NAC"
BN"5"131;
%"TAP"
"1","(3125,3325)","0","standard","I491";
;
CDS_LIB"standard"
BODY_TYPE"PLUMBING"
HDL_TAP"TRUE";
"B \NAC \NWC"1;
"S \NAC"
BN"4"132;
%"TAP"
"1","(3125,3525)","0","standard","I492";
;
CDS_LIB"standard"
BODY_TYPE"PLUMBING"
HDL_TAP"TRUE";
"B \NAC \NWC"1;
"S \NAC"
BN"8"128;
%"TAP"
"1","(3125,3425)","0","standard","I493";
;
CDS_LIB"standard"
BODY_TYPE"PLUMBING"
HDL_TAP"TRUE";
"B \NAC \NWC"1;
"S \NAC"
BN"6"130;
%"TAP"
"1","(3125,3475)","0","standard","I494";
;
CDS_LIB"standard"
BODY_TYPE"PLUMBING"
HDL_TAP"TRUE";
"B \NAC \NWC"1;
"S \NAC"
BN"7"129;
%"TAP"
"1","(3125,3625)","0","standard","I495";
;
CDS_LIB"standard"
BODY_TYPE"PLUMBING"
HDL_TAP"TRUE";
"B \NAC \NWC"1;
"S \NAC"
BN"10"126;
%"TAP"
"1","(3125,3575)","0","standard","I496";
;
CDS_LIB"standard"
BODY_TYPE"PLUMBING"
HDL_TAP"TRUE";
"B \NAC \NWC"1;
"S \NAC"
BN"9"127;
%"TAP"
"1","(3125,3775)","0","standard","I497";
;
CDS_LIB"standard"
BODY_TYPE"PLUMBING"
HDL_TAP"TRUE";
"B \NAC \NWC"1;
"S \NAC"
BN"13"123;
%"TAP"
"1","(3125,3725)","0","standard","I498";
;
CDS_LIB"standard"
BODY_TYPE"PLUMBING"
HDL_TAP"TRUE";
"B \NAC \NWC"1;
"S \NAC"
BN"12"124;
%"TAP"
"1","(3125,3675)","0","standard","I499";
;
CDS_LIB"standard"
BODY_TYPE"PLUMBING"
HDL_TAP"TRUE";
"B \NAC \NWC"1;
"S \NAC"
BN"11"125;
%"TAP"
"1","(3125,3875)","0","standard","I500";
;
CDS_LIB"standard"
BODY_TYPE"PLUMBING"
HDL_TAP"TRUE";
"B \NAC \NWC"1;
"S \NAC"
BN"15"121;
%"TAP"
"1","(3125,3825)","0","standard","I501";
;
CDS_LIB"standard"
BODY_TYPE"PLUMBING"
HDL_TAP"TRUE";
"B \NAC \NWC"1;
"S \NAC"
BN"14"122;
%"TAP"
"1","(3125,-375)","0","standard","I504";
;
CDS_LIB"standard"
BODY_TYPE"PLUMBING"
HDL_TAP"TRUE";
"B \NAC \NWC"6;
"S \NAC"
BN"2"54;
%"TAP"
"1","(3125,-425)","0","standard","I505";
;
CDS_LIB"standard"
BODY_TYPE"PLUMBING"
HDL_TAP"TRUE";
"B \NAC \NWC"6;
"S \NAC"
BN"1"55;
%"TAP"
"1","(3125,-475)","0","standard","I506";
;
CDS_LIB"standard"
BODY_TYPE"PLUMBING"
HDL_TAP"TRUE";
"B \NAC \NWC"6;
"S \NAC"
BN"0"56;
%"TAP"
"1","(3125,-275)","0","standard","I507";
;
CDS_LIB"standard"
BODY_TYPE"PLUMBING"
HDL_TAP"TRUE";
"B \NAC \NWC"6;
"S \NAC"
BN"4"52;
%"TAP"
"1","(3125,-325)","0","standard","I508";
;
CDS_LIB"standard"
BODY_TYPE"PLUMBING"
HDL_TAP"TRUE";
"B \NAC \NWC"6;
"S \NAC"
BN"3"53;
%"TAP"
"1","(3125,-125)","0","standard","I509";
;
CDS_LIB"standard"
BODY_TYPE"PLUMBING"
HDL_TAP"TRUE";
"B \NAC \NWC"6;
"S \NAC"
BN"7"49;
%"TAP"
"1","(3125,-175)","0","standard","I510";
;
CDS_LIB"standard"
BODY_TYPE"PLUMBING"
HDL_TAP"TRUE";
"B \NAC \NWC"6;
"S \NAC"
BN"6"50;
%"TAP"
"1","(3125,-225)","0","standard","I511";
;
CDS_LIB"standard"
BODY_TYPE"PLUMBING"
HDL_TAP"TRUE";
"B \NAC \NWC"6;
"S \NAC"
BN"5"51;
%"TAP"
"1","(3125,-75)","0","standard","I512";
;
CDS_LIB"standard"
BODY_TYPE"PLUMBING"
HDL_TAP"TRUE";
"B \NAC \NWC"6;
"S \NAC"
BN"8"48;
%"TAP"
"1","(3125,-25)","0","standard","I513";
;
CDS_LIB"standard"
BODY_TYPE"PLUMBING"
HDL_TAP"TRUE";
"B \NAC \NWC"6;
"S \NAC"
BN"9"47;
%"TAP"
"1","(3125,125)","0","standard","I514";
;
CDS_LIB"standard"
BODY_TYPE"PLUMBING"
HDL_TAP"TRUE";
"B \NAC \NWC"6;
"S \NAC"
BN"12"44;
%"TAP"
"1","(3125,25)","0","standard","I515";
;
CDS_LIB"standard"
BODY_TYPE"PLUMBING"
HDL_TAP"TRUE";
"B \NAC \NWC"6;
"S \NAC"
BN"10"46;
%"TAP"
"1","(3125,75)","0","standard","I516";
;
CDS_LIB"standard"
BODY_TYPE"PLUMBING"
HDL_TAP"TRUE";
"B \NAC \NWC"6;
"S \NAC"
BN"11"45;
%"TAP"
"1","(3125,175)","0","standard","I517";
;
CDS_LIB"standard"
BODY_TYPE"PLUMBING"
HDL_TAP"TRUE";
"B \NAC \NWC"6;
"S \NAC"
BN"13"43;
%"TAP"
"1","(3125,225)","0","standard","I518";
;
CDS_LIB"standard"
BODY_TYPE"PLUMBING"
HDL_TAP"TRUE";
"B \NAC \NWC"6;
"S \NAC"
BN"14"42;
%"TAP"
"1","(3125,275)","0","standard","I519";
;
CDS_LIB"standard"
BODY_TYPE"PLUMBING"
HDL_TAP"TRUE";
"B \NAC \NWC"6;
"S \NAC"
BN"15"41;
%"TAP"
"1","(3125,375)","0","standard","I520";
;
CDS_LIB"standard"
BODY_TYPE"PLUMBING"
HDL_TAP"TRUE";
"B \NAC \NWC"5;
"S \NAC"
BN"0"72;
%"TAP"
"1","(3125,525)","0","standard","I521";
;
CDS_LIB"standard"
BODY_TYPE"PLUMBING"
HDL_TAP"TRUE";
"B \NAC \NWC"5;
"S \NAC"
BN"3"69;
%"TAP"
"1","(3125,425)","0","standard","I522";
;
CDS_LIB"standard"
BODY_TYPE"PLUMBING"
HDL_TAP"TRUE";
"B \NAC \NWC"5;
"S \NAC"
BN"1"71;
%"TAP"
"1","(3125,475)","0","standard","I523";
;
CDS_LIB"standard"
BODY_TYPE"PLUMBING"
HDL_TAP"TRUE";
"B \NAC \NWC"5;
"S \NAC"
BN"2"70;
%"TAP"
"1","(3125,625)","0","standard","I524";
;
CDS_LIB"standard"
BODY_TYPE"PLUMBING"
HDL_TAP"TRUE";
"B \NAC \NWC"5;
"S \NAC"
BN"5"67;
%"TAP"
"1","(3125,575)","0","standard","I525";
;
CDS_LIB"standard"
BODY_TYPE"PLUMBING"
HDL_TAP"TRUE";
"B \NAC \NWC"5;
"S \NAC"
BN"4"68;
%"TAP"
"1","(3125,775)","0","standard","I526";
;
CDS_LIB"standard"
BODY_TYPE"PLUMBING"
HDL_TAP"TRUE";
"B \NAC \NWC"5;
"S \NAC"
BN"8"64;
%"TAP"
"1","(3125,675)","0","standard","I527";
;
CDS_LIB"standard"
BODY_TYPE"PLUMBING"
HDL_TAP"TRUE";
"B \NAC \NWC"5;
"S \NAC"
BN"6"66;
%"TAP"
"1","(3125,725)","0","standard","I528";
;
CDS_LIB"standard"
BODY_TYPE"PLUMBING"
HDL_TAP"TRUE";
"B \NAC \NWC"5;
"S \NAC"
BN"7"65;
%"TAP"
"1","(3125,875)","0","standard","I529";
;
CDS_LIB"standard"
BODY_TYPE"PLUMBING"
HDL_TAP"TRUE";
"B \NAC \NWC"5;
"S \NAC"
BN"10"62;
%"TAP"
"1","(3125,825)","0","standard","I530";
;
CDS_LIB"standard"
BODY_TYPE"PLUMBING"
HDL_TAP"TRUE";
"B \NAC \NWC"5;
"S \NAC"
BN"9"63;
%"TAP"
"1","(3125,1025)","0","standard","I531";
;
CDS_LIB"standard"
BODY_TYPE"PLUMBING"
HDL_TAP"TRUE";
"B \NAC \NWC"5;
"S \NAC"
BN"13"59;
%"TAP"
"1","(3125,975)","0","standard","I532";
;
CDS_LIB"standard"
BODY_TYPE"PLUMBING"
HDL_TAP"TRUE";
"B \NAC \NWC"5;
"S \NAC"
BN"12"60;
%"TAP"
"1","(3125,925)","0","standard","I533";
;
CDS_LIB"standard"
BODY_TYPE"PLUMBING"
HDL_TAP"TRUE";
"B \NAC \NWC"5;
"S \NAC"
BN"11"61;
%"TAP"
"1","(3125,1125)","0","standard","I534";
;
CDS_LIB"standard"
BODY_TYPE"PLUMBING"
HDL_TAP"TRUE";
"B \NAC \NWC"5;
"S \NAC"
BN"15"57;
%"TAP"
"1","(3125,1075)","0","standard","I535";
;
CDS_LIB"standard"
BODY_TYPE"PLUMBING"
HDL_TAP"TRUE";
"B \NAC \NWC"5;
"S \NAC"
BN"14"58;
END.
